(kicad_pcb
	(version 20260206)
	(generator "pcbnew")
	(generator_version "10.0")
	(general
		(thickness 1.6)
		(legacy_teardrops no)
	)
	(paper "A4")
	(title_block
		(title "peb — Lightning_PEB_BRD.brd")
		(comment 1 "Lightning (Wiwynn / Facebook NVMe JBOF) / footprints 856-861 of 2563")
	)
	(layers
		(0 "F.Cu" signal "TOP")
		(4 "In1.Cu" signal "L2GND")
		(6 "In2.Cu" signal "L3")
		(8 "In3.Cu" signal "L4VCC")
		(10 "In4.Cu" signal "L5VCC")
		(12 "In5.Cu" signal "L6")
		(14 "In6.Cu" signal "L7GND")
		(2 "B.Cu" signal "BOTTOM")
		(9 "F.Adhes" user "F.Adhesive")
		(11 "B.Adhes" user "B.Adhesive")
		(13 "F.Paste" user "Package Geometry/Pastemask Top")
		(15 "B.Paste" user "Package Geometry/Pastemask Bottom")
		(5 "F.SilkS" user "Ref Des/Silkscreen Top")
		(7 "B.SilkS" user "Ref Des/Silkscreen Bottom")
		(1 "F.Mask" user "Board Geometry/Soldermask Top")
		(3 "B.Mask" user "Board Geometry/Soldermask Bottom")
		(17 "Dwgs.User" user "User.Drawings")
		(19 "Cmts.User" user "User.Comments")
		(21 "Eco1.User" user "User.Eco1")
		(23 "Eco2.User" user "User.Eco2")
		(25 "Edge.Cuts" user "Board Geometry/Outline")
		(27 "Margin" user)
		(31 "F.CrtYd" user "Package Geometry/Place Bound Top")
		(29 "B.CrtYd" user "Package Geometry/Place Bound Bottom")
		(35 "F.Fab" user "Ref Des/Assembly Top")
		(33 "B.Fab" user "Ref Des/Assembly Bottom")
	)
	(footprint ""
		(layer "F.Cu")
		(at 159.807402 -55.272432 90)
		(property "Reference" "PR172"
			(at 0 0 90)
			(layer "F.SilkS")
			(hide yes)
			(effects
				(font
					(size 1.27 1.27)
				)
			)
		)
		(property "Value" "10D7R2F-GP"
			(at 0.064008 -3.993896 90)
			(unlocked yes)
			(layer "F.Fab")
			(hide yes)
			(effects
				(font
					(size 1.016 1.016)
					(thickness 0.1524)
				)
			)
		)
		(property "Device Type" "R402H16"
			(at 0.064008 -5.517896 90)
			(unlocked yes)
			(layer "F.Fab")
			(hide yes)
			(effects
				(font
					(size 1.016 1.016)
					(thickness 0.1524)
				)
			)
		)
		(duplicate_pad_numbers_are_jumpers no)
		(fp_line
			(start 0.508 -0.9398)
			(end -0.508 -0.9398)
			(stroke
				(width 0.1524)
				(type default)
			)
			(layer "F.SilkS")
		)
		(fp_line
			(start -0.508 -0.9398)
			(end -0.508 0.9398)
			(stroke
				(width 0.1524)
				(type default)
			)
			(layer "F.SilkS")
		)
		(fp_rect
			(start -0.508 0.9398)
			(end 0.508 -0.9398)
			(stroke
				(width 0)
				(type default)
			)
			(fill no)
			(layer "F.CrtYd")
		)
		(fp_rect
			(start -0.508 0.9398)
			(end 0.508 -0.9398)
			(stroke
				(width 0)
				(type default)
			)
			(fill no)
			(layer "F.Fab")
		)
		(pad "1" smd custom
			(at 0 -0.4445 90)
			(size 0.1397 0.1397)
			(layers "F.Cu" "F.Mask" "F.Paste")
			(net "P0V9_VFB_R")
			(options
				(clearance outline)
				(anchor circle)
			)
			(primitives
				(gr_poly
					(pts
						(arc
							(start -0.1778 -0.2794)
							(mid -0.249642 -0.249642)
							(end -0.2794 -0.1778)
						)
						(arc
							(start -0.2794 0.1778)
							(mid -0.249642 0.249642)
							(end -0.1778 0.2794)
						)
						(arc
							(start 0.1778 0.2794)
							(mid 0.249642 0.249642)
							(end 0.2794 0.1778)
						)
						(arc
							(start 0.2794 -0.1778)
							(mid 0.249642 -0.249642)
							(end 0.1778 -0.2794)
						)
					)
					(width 0)
					(fill yes)
				)
			)
		)
		(pad "2" smd custom
			(at 0 0.4445 90)
			(size 0.1397 0.1397)
			(layers "F.Cu" "F.Mask" "F.Paste")
			(net "P0V9")
			(options
				(clearance outline)
				(anchor circle)
			)
			(primitives
				(gr_poly
					(pts
						(arc
							(start -0.1778 -0.2794)
							(mid -0.249642 -0.249642)
							(end -0.2794 -0.1778)
						)
						(arc
							(start -0.2794 0.1778)
							(mid -0.249642 0.249642)
							(end -0.1778 0.2794)
						)
						(arc
							(start 0.1778 0.2794)
							(mid 0.249642 0.249642)
							(end 0.2794 0.1778)
						)
						(arc
							(start 0.2794 -0.1778)
							(mid 0.249642 -0.249642)
							(end 0.1778 -0.2794)
						)
					)
					(width 0)
					(fill yes)
				)
			)
		)
	)
	(footprint ""
		(layer "F.Cu")
		(at 201.00798 -212.420454 180)
		(property "Reference" "C116"
			(at 0 0 180)
			(layer "F.SilkS")
			(hide yes)
			(effects
				(font
					(size 1.27 1.27)
				)
			)
		)
		(property "Value" "SCD22U10V2KX-1GP"
			(at 1.1811 -2.7051 180)
			(unlocked yes)
			(layer "F.Fab")
			(hide yes)
			(effects
				(font
					(size 1.016 1.016)
					(thickness 0.1524)
				)
			)
		)
		(property "Device Type" "C402H22"
			(at 1.1811 -4.2291 180)
			(unlocked yes)
			(layer "F.Fab")
			(hide yes)
			(effects
				(font
					(size 1.016 1.016)
					(thickness 0.1524)
				)
			)
		)
		(duplicate_pad_numbers_are_jumpers no)
		(fp_rect
			(start -0.4318 0.9525)
			(end 0.4318 -0.9525)
			(stroke
				(width 0)
				(type default)
			)
			(fill no)
			(layer "F.CrtYd")
		)
		(fp_rect
			(start -0.4318 0.9525)
			(end 0.4318 -0.9525)
			(stroke
				(width 0)
				(type default)
			)
			(fill no)
			(layer "F.Fab")
		)
		(pad "1" smd custom
			(at 0 -0.4445 180)
			(size 0.1524 0.1524)
			(layers "F.Cu" "F.Mask" "F.Paste")
			(net "PCIE_TX_CAP_N42")
			(options
				(clearance outline)
				(anchor circle)
			)
			(primitives
				(gr_poly
					(pts
						(arc
							(start 0.3048 -0.2032)
							(mid 0.275042 -0.275042)
							(end 0.2032 -0.3048)
						)
						(arc
							(start -0.2032 -0.3048)
							(mid -0.275042 -0.275042)
							(end -0.3048 -0.2032)
						)
						(arc
							(start -0.3048 0.2032)
							(mid -0.275042 0.275042)
							(end -0.2032 0.3048)
						)
						(arc
							(start 0.2032 0.3048)
							(mid 0.275042 0.275042)
							(end 0.3048 0.2032)
						)
					)
					(width 0)
					(fill yes)
				)
			)
		)
		(pad "2" smd custom
			(at 0 0.4445 180)
			(size 0.1524 0.1524)
			(layers "F.Cu" "F.Mask" "F.Paste")
			(net "PCIE_TX_N42")
			(options
				(clearance outline)
				(anchor circle)
			)
			(primitives
				(gr_poly
					(pts
						(arc
							(start 0.3048 -0.2032)
							(mid 0.275042 -0.275042)
							(end 0.2032 -0.3048)
						)
						(arc
							(start -0.2032 -0.3048)
							(mid -0.275042 -0.275042)
							(end -0.3048 -0.2032)
						)
						(arc
							(start -0.3048 0.2032)
							(mid -0.275042 0.275042)
							(end -0.2032 0.3048)
						)
						(arc
							(start 0.2032 0.3048)
							(mid 0.275042 0.275042)
							(end 0.3048 0.2032)
						)
					)
					(width 0)
					(fill yes)
				)
			)
		)
	)
	(footprint ""
		(layer "F.Cu")
		(at 166.116 -89.5604 90)
		(property "Reference" "R3105"
			(at 0 0 90)
			(layer "F.SilkS")
			(hide yes)
			(effects
				(font
					(size 1.27 1.27)
				)
			)
		)
		(property "Value" "27R2F-GP"
			(at 0.064008 -3.993896 90)
			(unlocked yes)
			(layer "F.Fab")
			(hide yes)
			(effects
				(font
					(size 1.016 1.016)
					(thickness 0.1524)
				)
			)
		)
		(property "Device Type" "R402H16"
			(at 0.064008 -5.517896 90)
			(unlocked yes)
			(layer "F.Fab")
			(hide yes)
			(effects
				(font
					(size 1.016 1.016)
					(thickness 0.1524)
				)
			)
		)
		(duplicate_pad_numbers_are_jumpers no)
		(fp_line
			(start 0.508 -0.9398)
			(end -0.508 -0.9398)
			(stroke
				(width 0.1524)
				(type default)
			)
			(layer "F.SilkS")
		)
		(fp_line
			(start -0.508 -0.9398)
			(end -0.508 0.9398)
			(stroke
				(width 0.1524)
				(type default)
			)
			(layer "F.SilkS")
		)
		(fp_rect
			(start -0.508 0.9398)
			(end 0.508 -0.9398)
			(stroke
				(width 0)
				(type default)
			)
			(fill no)
			(layer "F.CrtYd")
		)
		(fp_rect
			(start -0.508 0.9398)
			(end 0.508 -0.9398)
			(stroke
				(width 0)
				(type default)
			)
			(fill no)
			(layer "F.Fab")
		)
		(pad "1" smd custom
			(at 0 -0.4445 90)
			(size 0.1397 0.1397)
			(layers "F.Cu" "F.Mask" "F.Paste")
			(net "CLKGEN_N1_R")
			(options
				(clearance outline)
				(anchor circle)
			)
			(primitives
				(gr_poly
					(pts
						(arc
							(start -0.1778 -0.2794)
							(mid -0.249642 -0.249642)
							(end -0.2794 -0.1778)
						)
						(arc
							(start -0.2794 0.1778)
							(mid -0.249642 0.249642)
							(end -0.1778 0.2794)
						)
						(arc
							(start 0.1778 0.2794)
							(mid 0.249642 0.249642)
							(end 0.2794 0.1778)
						)
						(arc
							(start 0.2794 -0.1778)
							(mid 0.249642 -0.249642)
							(end 0.1778 -0.2794)
						)
					)
					(width 0)
					(fill yes)
				)
			)
		)
		(pad "2" smd custom
			(at 0 0.4445 90)
			(size 0.1397 0.1397)
			(layers "F.Cu" "F.Mask" "F.Paste")
			(net "I210_REFCLK_D_N")
			(options
				(clearance outline)
				(anchor circle)
			)
			(primitives
				(gr_poly
					(pts
						(arc
							(start -0.1778 -0.2794)
							(mid -0.249642 -0.249642)
							(end -0.2794 -0.1778)
						)
						(arc
							(start -0.2794 0.1778)
							(mid -0.249642 0.249642)
							(end -0.1778 0.2794)
						)
						(arc
							(start 0.1778 0.2794)
							(mid 0.249642 0.249642)
							(end 0.2794 0.1778)
						)
						(arc
							(start 0.2794 -0.1778)
							(mid 0.249642 -0.249642)
							(end 0.1778 -0.2794)
						)
					)
					(width 0)
					(fill yes)
				)
			)
		)
	)
	(footprint ""
		(layer "F.Cu")
		(at 64.065912 -31.700216 -90)
		(property "Reference" "R739"
			(at 0 0 270)
			(layer "F.SilkS")
			(hide yes)
			(effects
				(font
					(size 1.27 1.27)
				)
			)
		)
		(property "Value" "0R2J-2-GP"
			(at 0.064008 -3.993896 270)
			(unlocked yes)
			(layer "F.Fab")
			(hide yes)
			(effects
				(font
					(size 1.016 1.016)
					(thickness 0.1524)
				)
			)
		)
		(property "Device Type" "R402H16"
			(at 0.064008 -5.517896 270)
			(unlocked yes)
			(layer "F.Fab")
			(hide yes)
			(effects
				(font
					(size 1.016 1.016)
					(thickness 0.1524)
				)
			)
		)
		(duplicate_pad_numbers_are_jumpers no)
		(fp_line
			(start -0.508 -0.9398)
			(end -0.508 0.9398)
			(stroke
				(width 0.1524)
				(type default)
			)
			(layer "F.SilkS")
		)
		(fp_line
			(start 0.508 -0.9398)
			(end -0.508 -0.9398)
			(stroke
				(width 0.1524)
				(type default)
			)
			(layer "F.SilkS")
		)
		(fp_rect
			(start -0.508 0.9398)
			(end 0.508 -0.9398)
			(stroke
				(width 0)
				(type default)
			)
			(fill no)
			(layer "F.CrtYd")
		)
		(fp_rect
			(start -0.508 0.9398)
			(end 0.508 -0.9398)
			(stroke
				(width 0)
				(type default)
			)
			(fill no)
			(layer "F.Fab")
		)
		(pad "1" smd custom
			(at 0 -0.4445 270)
			(size 0.1397 0.1397)
			(layers "F.Cu" "F.Mask" "F.Paste")
			(net "TRAY_MBP_CTRL_EN_N")
			(options
				(clearance outline)
				(anchor circle)
			)
			(primitives
				(gr_poly
					(pts
						(arc
							(start -0.1778 -0.2794)
							(mid -0.249642 -0.249642)
							(end -0.2794 -0.1778)
						)
						(arc
							(start -0.2794 0.1778)
							(mid -0.249642 0.249642)
							(end -0.1778 0.2794)
						)
						(arc
							(start 0.1778 0.2794)
							(mid 0.249642 0.249642)
							(end 0.2794 0.1778)
						)
						(arc
							(start 0.2794 -0.1778)
							(mid 0.249642 -0.249642)
							(end 0.1778 -0.2794)
						)
					)
					(width 0)
					(fill yes)
				)
			)
		)
		(pad "2" smd custom
			(at 0 0.4445 270)
			(size 0.1397 0.1397)
			(layers "F.Cu" "F.Mask" "F.Paste")
			(net "CN2_P23")
			(options
				(clearance outline)
				(anchor circle)
			)
			(primitives
				(gr_poly
					(pts
						(arc
							(start -0.1778 -0.2794)
							(mid -0.249642 -0.249642)
							(end -0.2794 -0.1778)
						)
						(arc
							(start -0.2794 0.1778)
							(mid -0.249642 0.249642)
							(end -0.1778 0.2794)
						)
						(arc
							(start 0.1778 0.2794)
							(mid 0.249642 0.249642)
							(end 0.2794 0.1778)
						)
						(arc
							(start 0.2794 -0.1778)
							(mid 0.249642 -0.249642)
							(end 0.1778 -0.2794)
						)
					)
					(width 0)
					(fill yes)
				)
			)
		)
	)
	(footprint ""
		(layer "F.Cu")
		(at 13.0302 -180.6956)
		(property "Reference" "R2110"
			(at 0 0 0)
			(layer "F.SilkS")
			(hide yes)
			(effects
				(font
					(size 1.27 1.27)
				)
			)
		)
		(property "Value" "1KR2J-1-GP"
			(at 0.064008 -3.993896 0)
			(unlocked yes)
			(layer "F.Fab")
			(hide yes)
			(effects
				(font
					(size 1.016 1.016)
					(thickness 0.1524)
				)
			)
		)
		(property "Device Type" "R402H16"
			(at 0.064008 -5.517896 0)
			(unlocked yes)
			(layer "F.Fab")
			(hide yes)
			(effects
				(font
					(size 1.016 1.016)
					(thickness 0.1524)
				)
			)
		)
		(duplicate_pad_numbers_are_jumpers no)
		(fp_line
			(start -0.508 -0.9398)
			(end -0.508 0.9398)
			(stroke
				(width 0.1524)
				(type default)
			)
			(layer "F.SilkS")
		)
		(fp_line
			(start 0.508 -0.9398)
			(end -0.508 -0.9398)
			(stroke
				(width 0.1524)
				(type default)
			)
			(layer "F.SilkS")
		)
		(fp_rect
			(start -0.508 0.9398)
			(end 0.508 -0.9398)
			(stroke
				(width 0)
				(type default)
			)
			(fill no)
			(layer "F.CrtYd")
		)
		(fp_rect
			(start -0.508 0.9398)
			(end 0.508 -0.9398)
			(stroke
				(width 0)
				(type default)
			)
			(fill no)
			(layer "F.Fab")
		)
		(pad "1" smd custom
			(at 0 -0.4445)
			(size 0.1397 0.1397)
			(layers "F.Cu" "F.Mask" "F.Paste")
			(net "MB0_CM_VOUT_R")
			(options
				(clearance outline)
				(anchor circle)
			)
			(primitives
				(gr_poly
					(pts
						(arc
							(start -0.1778 -0.2794)
							(mid -0.249642 -0.249642)
							(end -0.2794 -0.1778)
						)
						(arc
							(start -0.2794 0.1778)
							(mid -0.249642 0.249642)
							(end -0.1778 0.2794)
						)
						(arc
							(start 0.1778 0.2794)
							(mid 0.249642 0.249642)
							(end 0.2794 0.1778)
						)
						(arc
							(start 0.2794 -0.1778)
							(mid 0.249642 -0.249642)
							(end 0.1778 -0.2794)
						)
					)
					(width 0)
					(fill yes)
				)
			)
		)
		(pad "2" smd custom
			(at 0 0.4445)
			(size 0.1397 0.1397)
			(layers "F.Cu" "F.Mask" "F.Paste")
			(net "P12V")
			(options
				(clearance outline)
				(anchor circle)
			)
			(primitives
				(gr_poly
					(pts
						(arc
							(start -0.1778 -0.2794)
							(mid -0.249642 -0.249642)
							(end -0.2794 -0.1778)
						)
						(arc
							(start -0.2794 0.1778)
							(mid -0.249642 0.249642)
							(end -0.1778 0.2794)
						)
						(arc
							(start 0.1778 0.2794)
							(mid 0.249642 0.249642)
							(end 0.2794 0.1778)
						)
						(arc
							(start 0.2794 -0.1778)
							(mid 0.249642 -0.249642)
							(end 0.1778 -0.2794)
						)
					)
					(width 0)
					(fill yes)
				)
			)
		)
	)
	(footprint ""
		(layer "F.Cu")
		(at 161.163 -33.528)
		(property "Reference" "C400"
			(at 0 0 0)
			(layer "F.SilkS")
			(hide yes)
			(effects
				(font
					(size 1.27 1.27)
				)
			)
		)
		(property "Value" "SCD22U10V2KX-1GP"
			(at 1.1811 -2.7051 0)
			(unlocked yes)
			(layer "F.Fab")
			(hide yes)
			(effects
				(font
					(size 1.016 1.016)
					(thickness 0.1524)
				)
			)
		)
		(property "Device Type" "C402H22"
			(at 1.1811 -4.2291 0)
			(unlocked yes)
			(layer "F.Fab")
			(hide yes)
			(effects
				(font
					(size 1.016 1.016)
					(thickness 0.1524)
				)
			)
		)
		(duplicate_pad_numbers_are_jumpers no)
		(fp_rect
			(start -0.4318 0.9525)
			(end 0.4318 -0.9525)
			(stroke
				(width 0)
				(type default)
			)
			(fill no)
			(layer "F.CrtYd")
		)
		(fp_rect
			(start -0.4318 0.9525)
			(end 0.4318 -0.9525)
			(stroke
				(width 0)
				(type default)
			)
			(fill no)
			(layer "F.Fab")
		)
		(pad "1" smd custom
			(at 0 -0.4445)
			(size 0.1524 0.1524)
			(layers "F.Cu" "F.Mask" "F.Paste")
			(net "PCIE_TX_CAP_P90")
			(options
				(clearance outline)
				(anchor circle)
			)
			(primitives
				(gr_poly
					(pts
						(arc
							(start 0.3048 -0.2032)
							(mid 0.275042 -0.275042)
							(end 0.2032 -0.3048)
						)
						(arc
							(start -0.2032 -0.3048)
							(mid -0.275042 -0.275042)
							(end -0.3048 -0.2032)
						)
						(arc
							(start -0.3048 0.2032)
							(mid -0.275042 0.275042)
							(end -0.2032 0.3048)
						)
						(arc
							(start 0.2032 0.3048)
							(mid 0.275042 0.275042)
							(end 0.3048 0.2032)
						)
					)
					(width 0)
					(fill yes)
				)
			)
		)
		(pad "2" smd custom
			(at 0 0.4445)
			(size 0.1524 0.1524)
			(layers "F.Cu" "F.Mask" "F.Paste")
			(net "PCIE_TX_P90")
			(options
				(clearance outline)
				(anchor circle)
			)
			(primitives
				(gr_poly
					(pts
						(arc
							(start 0.3048 -0.2032)
							(mid 0.275042 -0.275042)
							(end 0.2032 -0.3048)
						)
						(arc
							(start -0.2032 -0.3048)
							(mid -0.275042 -0.275042)
							(end -0.3048 -0.2032)
						)
						(arc
							(start -0.3048 0.2032)
							(mid -0.275042 0.275042)
							(end -0.2032 0.3048)
						)
						(arc
							(start 0.2032 0.3048)
							(mid 0.275042 0.275042)
							(end 0.3048 0.2032)
						)
					)
					(width 0)
					(fill yes)
				)
			)
		)
	)
)
